(kicad_pcb
	(version 20241229)
	(generator "pcbnew")
	(generator_version "9.0")
	(general
		(thickness 1.61)
		(legacy_teardrops no)
	)
	(paper "A3")
	(title_block
		(title "RDIMM DDR5 Tester")
		(date "2026-05-21")
		(rev "2.2.0")
		(company "Antmicro")
		(comment 9 "footprints 37-39 of 796")
	)
	(layers
		(0 "F.Cu" signal)
		(4 "In1.Cu" power)
		(6 "In2.Cu" mixed)
		(8 "In3.Cu" power)
		(10 "In4.Cu" mixed)
		(12 "In5.Cu" power)
		(14 "In6.Cu" mixed)
		(16 "In7.Cu" power)
		(18 "In8.Cu" power)
		(20 "In9.Cu" mixed)
		(22 "In10.Cu" power)
		(2 "B.Cu" signal)
		(9 "F.Adhes" user "F.Adhesive")
		(11 "B.Adhes" user "B.Adhesive")
		(13 "F.Paste" user)
		(15 "B.Paste" user)
		(5 "F.SilkS" user "F.Silkscreen")
		(7 "B.SilkS" user "B.Silkscreen")
		(1 "F.Mask" user)
		(3 "B.Mask" user)
		(17 "Dwgs.User" user "User.Drawings")
		(19 "Cmts.User" user "User.Comments")
		(21 "Eco1.User" user "User.Eco1")
		(23 "Eco2.User" user "User.Eco2")
		(25 "Edge.Cuts" user)
		(27 "Margin" user)
		(31 "F.CrtYd" user "F.Courtyard")
		(29 "B.CrtYd" user "B.Courtyard")
		(35 "F.Fab" user)
		(33 "B.Fab" user)
	)
	(footprint "antmicro-footprints:R_0402_1005Metric"
		(layer "F.Cu")
		(at 141.525 139.807851 -90)
		(descr "Resistor SMD 0402")
		(tags "resistor SMD 0402")
		(property "Reference" "R112"
			(at -1.063186 0.852303 90)
			(layer "F.SilkS")
			(effects
				(font
					(size 0.7 0.7)
					(thickness 0.15)
				)
				(justify right bottom)
			)
		)
		(property "Value" "R_12k1_0402"
			(at -1.011843 1.772047 90)
			(layer "F.Fab")
			(effects
				(font
					(size 0.7 0.7)
					(thickness 0.15)
				)
				(justify right bottom)
			)
		)
		(property "Datasheet" "https://www.bourns.com/docs/product-datasheets/cr.pdf"
			(at 0 0 270)
			(layer "F.Fab")
			(hide yes)
			(effects
				(font
					(size 1.27 1.27)
					(thickness 0.15)
				)
			)
		)
		(property "Manufacturer" "Bourns"
			(at 0 0 270)
			(unlocked yes)
			(layer "F.Fab")
			(hide yes)
			(effects
				(font
					(size 1 1)
					(thickness 0.15)
				)
			)
		)
		(property "MPN" "CR0402-FX-1212GLF"
			(at 0 0 270)
			(unlocked yes)
			(layer "F.Fab")
			(hide yes)
			(effects
				(font
					(size 1 1)
					(thickness 0.15)
				)
			)
		)
		(property "Val" "12k1"
			(at 0 0 270)
			(unlocked yes)
			(layer "F.Fab")
			(hide yes)
			(effects
				(font
					(size 1 1)
					(thickness 0.15)
				)
			)
		)
		(property "License" "Apache-2.0"
			(at 0 0 270)
			(unlocked yes)
			(layer "F.Fab")
			(hide yes)
			(effects
				(font
					(size 1 1)
					(thickness 0.15)
				)
			)
		)
		(property "Author" "Antmicro"
			(at 0 0 270)
			(unlocked yes)
			(layer "F.Fab")
			(hide yes)
			(effects
				(font
					(size 1 1)
					(thickness 0.15)
				)
			)
		)
		(property "Tolerance" "1%"
			(at 0 0 270)
			(unlocked yes)
			(layer "F.Fab")
			(hide yes)
			(effects
				(font
					(size 1 1)
					(thickness 0.15)
				)
			)
		)
		(sheetname "/Ethernet/")
		(sheetfile "ethernet.kicad_sch")
		(attr smd)
		(fp_rect
			(start -0.925 -0.47)
			(end 0.925 0.47)
			(stroke
				(width 0.05)
				(type default)
			)
			(fill no)
			(layer "F.CrtYd")
		)
		(fp_rect
			(start -0.5 -0.25)
			(end 0.5 0.25)
			(stroke
				(width 0.15)
				(type solid)
			)
			(fill no)
			(layer "F.Fab")
		)
		(fp_text user "${REFERENCE}"
			(at -0.95 3.168 270)
			(layer "F.Fab")
			(effects
				(font
					(size 0.7 0.7)
					(thickness 0.15)
				)
				(justify left bottom)
			)
		)
		(fp_text user "Author: Antmicro"
			(at -0.95 4.169 270)
			(layer "F.Fab")
			(effects
				(font
					(size 0.7 0.7)
					(thickness 0.15)
				)
				(justify left bottom)
			)
		)
		(fp_text user "License: Apache-2.0"
			(at -0.95 5.169 270)
			(layer "F.Fab")
			(effects
				(font
					(size 0.7 0.7)
					(thickness 0.15)
				)
				(justify left bottom)
			)
		)
		(pad "1" smd roundrect
			(at -0.48 0 270)
			(size 0.59 0.64)
			(layers "F.Cu" "F.Mask" "F.Paste")
			(roundrect_rratio 0.25)
			(net 1 "GND")
			(pintype "passive")
		)
		(pad "2" smd roundrect
			(at 0.48 0 270)
			(size 0.59 0.64)
			(layers "F.Cu" "F.Mask" "F.Paste")
			(roundrect_rratio 0.25)
			(net 302 "Net-(U15-ISET)")
			(pintype "passive")
		)
	)
	(footprint "antmicro-footprints:R_0402_1005Metric"
		(layer "F.Cu")
		(at 141.525 141.807851 90)
		(descr "Resistor SMD 0402")
		(tags "resistor SMD 0402")
		(property "Reference" "R100"
			(at -2.617149 -0.875 90)
			(layer "F.SilkS")
			(effects
				(font
					(size 0.7 0.7)
					(thickness 0.15)
				)
				(justify left bottom)
			)
		)
		(property "Value" "R_1M8_0402"
			(at -1.011843 1.772047 90)
			(layer "F.Fab")
			(effects
				(font
					(size 0.7 0.7)
					(thickness 0.15)
				)
				(justify left bottom)
			)
		)
		(property "Datasheet" "https://www.bourns.com/docs/product-datasheets/cr.pdf"
			(at 0 0 90)
			(layer "F.Fab")
			(hide yes)
			(effects
				(font
					(size 1.27 1.27)
					(thickness 0.15)
				)
			)
		)
		(property "Manufacturer" "Bourns"
			(at 0 0 90)
			(unlocked yes)
			(layer "F.Fab")
			(hide yes)
			(effects
				(font
					(size 1 1)
					(thickness 0.15)
				)
			)
		)
		(property "MPN" "CR0402-FX-1804GLF"
			(at 0 0 90)
			(unlocked yes)
			(layer "F.Fab")
			(hide yes)
			(effects
				(font
					(size 1 1)
					(thickness 0.15)
				)
			)
		)
		(property "Val" "1M8"
			(at 0 0 90)
			(unlocked yes)
			(layer "F.Fab")
			(hide yes)
			(effects
				(font
					(size 1 1)
					(thickness 0.15)
				)
			)
		)
		(property "License" "Apache-2.0"
			(at 0 0 90)
			(unlocked yes)
			(layer "F.Fab")
			(hide yes)
			(effects
				(font
					(size 1 1)
					(thickness 0.15)
				)
			)
		)
		(property "Author" "Antmicro"
			(at 0 0 90)
			(unlocked yes)
			(layer "F.Fab")
			(hide yes)
			(effects
				(font
					(size 1 1)
					(thickness 0.15)
				)
			)
		)
		(property "Tolerance" "1%"
			(at 0 0 90)
			(unlocked yes)
			(layer "F.Fab")
			(hide yes)
			(effects
				(font
					(size 1 1)
					(thickness 0.15)
				)
			)
		)
		(sheetname "/Ethernet/")
		(sheetfile "ethernet.kicad_sch")
		(attr smd)
		(fp_rect
			(start -0.925 -0.47)
			(end 0.925 0.47)
			(stroke
				(width 0.05)
				(type default)
			)
			(fill no)
			(layer "F.CrtYd")
		)
		(fp_rect
			(start -0.5 -0.25)
			(end 0.5 0.25)
			(stroke
				(width 0.15)
				(type solid)
			)
			(fill no)
			(layer "F.Fab")
		)
		(fp_text user "Author: Antmicro"
			(at -0.95 4.169 90)
			(layer "F.Fab")
			(effects
				(font
					(size 0.7 0.7)
					(thickness 0.15)
				)
				(justify left bottom)
			)
		)
		(fp_text user "License: Apache-2.0"
			(at -0.95 5.169 90)
			(layer "F.Fab")
			(effects
				(font
					(size 0.7 0.7)
					(thickness 0.15)
				)
				(justify left bottom)
			)
		)
		(fp_text user "${REFERENCE}"
			(at -0.95 3.168 90)
			(layer "F.Fab")
			(effects
				(font
					(size 0.7 0.7)
					(thickness 0.15)
				)
				(justify left bottom)
			)
		)
		(pad "1" smd roundrect
			(at -0.48 0 90)
			(size 0.59 0.64)
			(layers "F.Cu" "F.Mask" "F.Paste")
			(roundrect_rratio 0.25)
			(net 228 "Net-(U15-XO)")
			(pintype "passive")
		)
		(pad "2" smd roundrect
			(at 0.48 0 90)
			(size 0.59 0.64)
			(layers "F.Cu" "F.Mask" "F.Paste")
			(roundrect_rratio 0.25)
			(net 227 "Net-(U15-XI)")
			(pintype "passive")
		)
	)
	(footprint "antmicro-footprints:Resonator_SMD_Abracon_ABM8G_3.2x2.5mm"
		(layer "F.Cu")
		(at 144.425 141.007851)
		(property "Reference" "Y2"
			(at 3.3 1.542149 0)
			(layer "F.SilkS")
			(effects
				(font
					(size 0.7 0.7)
					(thickness 0.15)
				)
				(justify right bottom)
			)
		)
		(property "Value" "Resonator_25MHz_ABM8G"
			(at -1.75 2.548 0)
			(layer "F.Fab")
			(effects
				(font
					(size 0.7 0.7)
					(thickness 0.15)
				)
				(justify left bottom)
			)
		)
		(property "Datasheet" "https://abracon.com/Resonators/ABM8G.pdf"
			(at 0 0 0)
			(layer "F.Fab")
			(hide yes)
			(effects
				(font
					(size 1.27 1.27)
					(thickness 0.15)
				)
			)
		)
		(property "MPN" "ABM8G-25.000MHZ-18-D2Y-T3"
			(at 0 0 0)
			(unlocked yes)
			(layer "F.Fab")
			(hide yes)
			(effects
				(font
					(size 1 1)
					(thickness 0.15)
				)
			)
		)
		(property "Manufacturer" "Abracon"
			(at 0 0 0)
			(unlocked yes)
			(layer "F.Fab")
			(hide yes)
			(effects
				(font
					(size 1 1)
					(thickness 0.15)
				)
			)
		)
		(property "Author" "Antmicro"
			(at 0 0 0)
			(unlocked yes)
			(layer "F.Fab")
			(hide yes)
			(effects
				(font
					(size 1 1)
					(thickness 0.15)
				)
			)
		)
		(property "License" "Apache-2.0"
			(at 0 0 0)
			(unlocked yes)
			(layer "F.Fab")
			(hide yes)
			(effects
				(font
					(size 1 1)
					(thickness 0.15)
				)
			)
		)
		(property "Val" "25 MHz"
			(at 0 0 0)
			(unlocked yes)
			(layer "F.Fab")
			(hide yes)
			(effects
				(font
					(size 1 1)
					(thickness 0.15)
				)
			)
		)
		(sheetname "/Ethernet/")
		(sheetfile "ethernet.kicad_sch")
		(attr smd)
		(fp_line
			(start -1.6 0.3)
			(end -1.6 -0.2)
			(stroke
				(width 0.15)
				(type solid)
			)
			(layer "F.SilkS")
		)
		(fp_line
			(start -0.35 -1.25)
			(end 0.45 -1.25)
			(stroke
				(width 0.15)
				(type solid)
			)
			(layer "F.SilkS")
		)
		(fp_line
			(start -0.35 1.25)
			(end 0.45 1.25)
			(stroke
				(width 0.15)
				(type solid)
			)
			(layer "F.SilkS")
		)
		(fp_line
			(start 1.6 0.3)
			(end 1.6 -0.2)
			(stroke
				(width 0.15)
				(type solid)
			)
			(layer "F.SilkS")
		)
		(fp_circle
			(center -1.75 1.5)
			(end -1.7 1.5)
			(stroke
				(width 0.15)
				(type solid)
			)
			(fill no)
			(layer "F.SilkS")
		)
		(fp_rect
			(start -1.907 -1.55)
			(end 2.006 1.649)
			(stroke
				(width 0.05)
				(type solid)
			)
			(fill no)
			(layer "F.CrtYd")
		)
		(fp_text user "Author: Antmicro"
			(at -1.75 5 0)
			(layer "F.Fab")
			(effects
				(font
					(size 0.7 0.7)
					(thickness 0.15)
				)
				(justify left bottom)
			)
		)
		(fp_text user "License: Apache-2.0"
			(at -1.75 6.5 0)
			(layer "F.Fab")
			(effects
				(font
					(size 0.7 0.7)
					(thickness 0.15)
				)
				(justify left bottom)
			)
		)
		(fp_text user "${REFERENCE}"
			(at -1.75 3.75 0)
			(layer "F.Fab")
			(effects
				(font
					(size 0.7 0.7)
					(thickness 0.15)
				)
				(justify left bottom)
			)
		)
		(pad "1" smd roundrect
			(at -1.101 0.949)
			(size 1.3 1.1)
			(layers "F.Cu" "F.Mask" "F.Paste")
			(roundrect_rratio 0)
			(chamfer_ratio 0.2)
			(chamfer bottom_left)
			(net 228 "Net-(U15-XO)")
			(pintype "passive")
		)
		(pad "2" smd rect
			(at 1.199 0.949)
			(size 1.3 1.1)
			(layers "F.Cu" "F.Mask" "F.Paste")
			(net 1 "GND")
			(pinfunction "SH")
			(pintype "passive")
		)
		(pad "3" smd rect
			(at 1.199 -0.85)
			(size 1.3 1.1)
			(layers "F.Cu" "F.Mask" "F.Paste")
			(net 227 "Net-(U15-XI)")
			(pintype "passive")
		)
		(pad "4" smd rect
			(at -1.101 -0.85)
			(size 1.3 1.1)
			(layers "F.Cu" "F.Mask" "F.Paste")
			(net 1 "GND")
			(pinfunction "SH")
			(pintype "passive")
		)
	)
)
